FILE_TYPE = CONNECTIVITY;
{Allegro Design Entry HDL 17.2-2016 S081 (4005846) 1/11/2022}
"PAGE_NUMBER" = 71;
0"NC";
1"GND\g";
2"GND\g";
3"GND\g";
4"GND\g";
5"GND\g";
6"GND\g";
%"UNIVERSAL_GND"
"1","(-3825,-775)","0","logical_power","I1";
;
CDS_LIB"logical_power"
HDL_POWER"GND";
"A"6;
%"SOCKET4677_AZIF0045P001C01CS"
"34","(-2375,1750)","0","pure_quanta","I2";
;
PART_NUMBER"DGA^7000023"
PART_TYPE"SMLF"
MATERIAL"IO"
VALUE"SOCKET4677_AZIF0045-P001C01CS"
$LOCATION"U1"
CDS_LIB"pure_quanta"
NEEDS_NO_SIZE"TRUE"
CDS_LMAN_SYM_OUTLINE"-1050,2150,1050,-2100"
CDS_LOCATION"U1"
$SEC"34"
CDS_SEC"34";
"VSS723"
$PN"DB91"5;
"VSS724"
$PN"DC1"5;
"VSS725"
$PN"DC13"5;
"VSS726"
$PN"DC21"5;
"VSS735"
$PN"DC52"5;
"VSS738"
$PN"DC58"5;
"VSS739"
$PN"DC64"5;
"VSS747"
$PN"DD12"5;
"VSS748"
$PN"DD16"5;
"VSS753"
$PN"DD49"5;
"VSS776"
$PN"DE39"5;
"VSS791"
$PN"DE70"5;
"VSS798"
$PN"DF12"5;
"VSS799"
$PN"DF16"5;
"VSS802"
$PN"DF49"5;
"VSS806"
$PN"DF91"5;
"VSS807"
$PN"DG1"5;
"VSS808"
$PN"DG13"5;
"VSS809"
$PN"DG21"5;
"VSS817"
$PN"DG52"5;
"VSS820"
$PN"DG58"5;
"VSS821"
$PN"DG64"5;
"VSS829"
$PN"DH16"6;
"VSS830"
$PN"DH20"6;
"VSS832"
$PN"DH26"6;
"VSS835"
$PN"DH34"6;
"VSS839"
$PN"DH44"6;
"VSS841"
$PN"DH51"6;
"VSS842"
$PN"DH53"6;
"VSS844"
$PN"DH59"6;
"VSS845"
$PN"DH63"6;
"VSS847"
$PN"DH69"6;
"VSS849"
$PN"DH75"6;
"VSS857"
$PN"DJ25"6;
"VSS861"
$PN"DJ35"6;
"VSS867"
$PN"DJ54"6;
"VSS870"
$PN"DJ62"6;
"VSS872"
$PN"DJ68"6;
"VSS880"
$PN"DK12"6;
"VSS882"
$PN"DK18"6;
"VSS883"
$PN"DK24"6;
"VSS887"
$PN"DK42"6;
"VSS890"
$PN"DK55"6;
"VSS893"
$PN"DK61"6;
"VSS894"
$PN"DK67"6;
"VSS903"
$PN"DL1"6;
"VSS904"
$PN"DL13"6;
"VSS905"
$PN"DL17"6;
"VSS908"
$PN"DL5"6;
"VSS909"
$PN"DL52"6;
"VSS949"
$PN"DC27"5;
"VSS950"
$PN"DC33"5;
"VSS951"
$PN"DC39"5;
"VSS952"
$PN"DC45"5;
"VSS953"
$PN"DC5"5;
"VSS954"
$PN"DC70"5;
"VSS956"
$PN"DC76"5;
"VSS958"
$PN"DC78"5;
"VSS960"
$PN"DC80"5;
"VSS961"
$PN"DC84"5;
"VSS962"
$PN"DC88"5;
"VSS963"
$PN"DC9"5;
"VSS964"
$PN"DD4"5;
"VSS965"
$PN"DD79"5;
"VSS967"
$PN"DD8"5;
"VSS970"
$PN"DE17"5;
"VSS971"
$PN"DE19"5;
"VSS972"
$PN"DE21"5;
"VSS974"
$PN"DE23"5;
"VSS975"
$PN"DE25"5;
"VSS977"
$PN"DE27"5;
"VSS978"
$PN"DE29"5;
"VSS981"
$PN"DE31"5;
"VSS982"
$PN"DE33"5;
"VSS983"
$PN"DE35"5;
"VSS984"
$PN"DE37"5;
"VSS986"
$PN"DE41"5;
"VSS987"
$PN"DE43"5;
"VSS988"
$PN"DE45"5;
"VSS989"
$PN"DE48"5;
"VSS991"
$PN"DE50"5;
"VSS992"
$PN"DE52"5;
"VSS994"
$PN"DE54"5;
"VSS995"
$PN"DE56"5;
"VSS996"
$PN"DE58"5;
"VSS997"
$PN"DE60"5;
"VSS999"
$PN"DE62"5;
"VSS1001"
$PN"DE64"5;
"VSS1004"
$PN"DE66"5;
"VSS1007"
$PN"DE68"5;
"VSS1008"
$PN"DE72"5;
"VSS1009"
$PN"DE74"5;
"VSS1010"
$PN"DE76"5;
"VSS1011"
$PN"DE82"5;
"VSS1012"
$PN"DE84"5;
"VSS1015"
$PN"DE88"5;
"VSS1017"
$PN"DF4"5;
"VSS1018"
$PN"DF79"5;
"VSS1019"
$PN"DF8"5;
"VSS1020"
$PN"DF87"5;
"VSS1022"
$PN"DG27"5;
"VSS1024"
$PN"DG33"5;
"VSS1027"
$PN"DG39"5;
"VSS1030"
$PN"DG45"5;
"VSS1031"
$PN"DG5"5;
"VSS1032"
$PN"DG70"5;
"VSS1033"
$PN"DG76"5;
"VSS1034"
$PN"DG80"6;
"VSS1035"
$PN"DG84"6;
"VSS1037"
$PN"DG88"6;
"VSS1038"
$PN"DG9"5;
"VSS1039"
$PN"DH12"6;
"VSS1040"
$PN"DH22"6;
"VSS1041"
$PN"DH28"6;
"VSS1042"
$PN"DH32"6;
"VSS1043"
$PN"DH38"6;
"VSS1044"
$PN"DH4"6;
"VSS1045"
$PN"DH40"6;
"VSS1046"
$PN"DH47"6;
"VSS1049"
$PN"DH57"6;
"VSS1053"
$PN"DH65"6;
"VSS1055"
$PN"DH71"6;
"VSS1056"
$PN"DH77"6;
"VSS1057"
$PN"DH8"6;
"VSS1058"
$PN"DH85"6;
"VSS1061"
$PN"DJ19"6;
"VSS1062"
$PN"DJ23"6;
"VSS1065"
$PN"DJ29"6;
"VSS1066"
$PN"DJ31"6;
"VSS1067"
$PN"DJ37"6;
"VSS1068"
$PN"DJ41"6;
"VSS1069"
$PN"DJ43"6;
"VSS1070"
$PN"DJ48"6;
"VSS1071"
$PN"DJ50"6;
"VSS1072"
$PN"DJ56"6;
"VSS1073"
$PN"DJ60"6;
"VSS1074"
$PN"DJ66"6;
"VSS1075"
$PN"DJ72"6;
"VSS1076"
$PN"DJ74"6;
"VSS1078"
$PN"DJ80"6;
"VSS1079"
$PN"DJ82"6;
"VSS1080"
$PN"DJ84"6;
"VSS1081"
$PN"DJ88"6;
"VSS1082"
$PN"DK16"6;
"VSS1083"
$PN"DK30"6;
"VSS1084"
$PN"DK36"6;
"VSS1085"
$PN"DK4"6;
"VSS1086"
$PN"DK49"6;
"VSS1087"
$PN"DK73"6;
"VSS1088"
$PN"DK77"6;
"VSS1089"
$PN"DK79"6;
"VSS1090"
$PN"DK8"6;
"VSS1091"
$PN"DK81"6;
"VSS1092"
$PN"DK83"6;
"VSS1093"
$PN"DK87"6;
"VSS1094"
$PN"DK91"6;
"VSS1095"
$PN"DL39"6;
"VSS1096"
$PN"DL84"6;
"VSS1098"
$PN"DL88"6;
"VSS1099"
$PN"DL9"6;
%"UNIVERSAL_GND"
"1","(-925,-775)","0","logical_power","I3";
;
CDS_LIB"logical_power"
HDL_POWER"GND";
"A"5;
%"UNIVERSAL_GND"
"1","(-775,-775)","0","logical_power","I4";
;
CDS_LIB"logical_power"
HDL_POWER"GND";
"A"4;
%"SOCKET4677_AZIF0045P001C01CS"
"35","(675,1750)","0","pure_quanta","I5";
;
PART_NUMBER"DGA^7000023"
PART_TYPE"SMLF"
MATERIAL"IO"
VALUE"SOCKET4677_AZIF0045-P001C01CS"
$LOCATION"U1"
CDS_LIB"pure_quanta"
NEEDS_NO_SIZE"TRUE"
CDS_LMAN_SYM_OUTLINE"-1050,2150,1050,-2100"
CDS_LOCATION"U1"
$SEC"35"
CDS_SEC"35";
"VSS436"
$PN"CM16"3;
"VSS438"
$PN"CM22"3;
"VSS471"
$PN"CN76"3;
"VSS478"
$PN"CP16"3;
"VSS493"
$PN"CP79"3;
"VSS514"
$PN"CR78"3;
"VSS521"
$PN"CT16"3;
"VSS526"
$PN"CT4"3;
"VSS534"
$PN"CT8"3;
"VSS537"
$PN"CT89"3;
"VSS544"
$PN"CU25"3;
"VSS553"
$PN"CU72"3;
"VSS554"
$PN"CU78"3;
"VSS558"
$PN"CV16"4;
"VSS562"
$PN"CV26"4;
"VSS571"
$PN"CV79"4;
"VSS583"
$PN"CW33"4;
"VSS595"
$PN"CW70"4;
"VSS611"
$PN"CY4"4;
"VSS679"
$PN"DA43"4;
"VSS690"
$PN"DA68"4;
"VSS699"
$PN"DB16"4;
"VSS700"
$PN"DB20"4;
"VSS702"
$PN"DB26"4;
"VSS705"
$PN"DB34"4;
"VSS709"
$PN"DB44"4;
"VSS711"
$PN"DB51"4;
"VSS712"
$PN"DB53"4;
"VSS714"
$PN"DB59"4;
"VSS715"
$PN"DB63"4;
"VSS717"
$PN"DB69"4;
"VSS719"
$PN"DB75"4;
"VSS744"
$PN"CK63"3;
"VSS745"
$PN"CK69"3;
"VSS749"
$PN"CK81"3;
"VSS750"
$PN"CL1"3;
"VSS751"
$PN"CL13"3;
"VSS752"
$PN"CL17"3;
"VSS754"
$PN"CL5"3;
"VSS755"
$PN"CL62"3;
"VSS756"
$PN"CL74"3;
"VSS757"
$PN"CL78"3;
"VSS758"
$PN"CL80"3;
"VSS759"
$PN"CL82"3;
"VSS760"
$PN"CL9"3;
"VSS761"
$PN"CM12"3;
"VSS762"
$PN"CM20"3;
"VSS763"
$PN"CM24"3;
"VSS764"
$PN"CM4"3;
"VSS765"
$PN"CM61"3;
"VSS766"
$PN"CM65"3;
"VSS767"
$PN"CM67"3;
"VSS768"
$PN"CM79"3;
"VSS769"
$PN"CM8"3;
"VSS770"
$PN"CM81"3;
"VSS771"
$PN"CM83"3;
"VSS772"
$PN"CM85"3;
"VSS773"
$PN"CN68"3;
"VSS774"
$PN"CN70"3;
"VSS775"
$PN"CN72"3;
"VSS777"
$PN"CN74"3;
"VSS778"
$PN"CN84"3;
"VSS779"
$PN"CN86"3;
"VSS780"
$PN"CP12"3;
"VSS781"
$PN"CP18"3;
"VSS782"
$PN"CP4"3;
"VSS783"
$PN"CP75"3;
"VSS784"
$PN"CP77"3;
"VSS785"
$PN"CP8"3;
"VSS786"
$PN"CP83"3;
"VSS787"
$PN"CP87"3;
"VSS788"
$PN"CP91"3;
"VSS789"
$PN"CR1"3;
"VSS790"
$PN"CR11"3;
"VSS792"
$PN"CR13"3;
"VSS793"
$PN"CR17"3;
"VSS794"
$PN"CR5"3;
"VSS795"
$PN"CR62"3;
"VSS796"
$PN"CR64"3;
"VSS797"
$PN"CR84"3;
"VSS800"
$PN"CR88"3;
"VSS801"
$PN"CR9"3;
"VSS803"
$PN"CR90"3;
"VSS804"
$PN"CT10"3;
"VSS805"
$PN"CT12"3;
"VSS810"
$PN"CT69"3;
"VSS811"
$PN"CT73"3;
"VSS812"
$PN"CT81"3;
"VSS813"
$PN"CU19"3;
"VSS814"
$PN"CU21"3;
"VSS815"
$PN"CU23"3;
"VSS816"
$PN"CU60"3;
"VSS818"
$PN"CU66"3;
"VSS819"
$PN"CU68"3;
"VSS822"
$PN"CU84"3;
"VSS823"
$PN"CU88"3;
"VSS824"
$PN"CV12"3;
"VSS825"
$PN"CV4"3;
"VSS826"
$PN"CV75"4;
"VSS827"
$PN"CV8"3;
"VSS828"
$PN"CV83"4;
"VSS831"
$PN"CV87"4;
"VSS833"
$PN"CV91"4;
"VSS834"
$PN"CW1"4;
"VSS836"
$PN"CW13"4;
"VSS837"
$PN"CW17"4;
"VSS838"
$PN"CW5"4;
"VSS840"
$PN"CW72"4;
"VSS843"
$PN"CW78"4;
"VSS846"
$PN"CW84"4;
"VSS848"
$PN"CW88"4;
"VSS850"
$PN"CW9"4;
"VSS851"
$PN"CY12"4;
"VSS852"
$PN"CY16"4;
"VSS853"
$PN"CY18"4;
"VSS854"
$PN"CY26"4;
"VSS855"
$PN"CY30"4;
"VSS856"
$PN"CY63"4;
"VSS858"
$PN"CY73"4;
"VSS859"
$PN"CY77"4;
"VSS860"
$PN"CY8"4;
"VSS862"
$PN"CY81"4;
"VSS863"
$PN"CY83"4;
"VSS910"
$PN"DA19"4;
"VSS911"
$PN"DA23"4;
"VSS912"
$PN"DA25"4;
"VSS913"
$PN"DA29"4;
"VSS914"
$PN"DA31"4;
"VSS915"
$PN"DA33"4;
"VSS916"
$PN"DA35"4;
"VSS917"
$PN"DA37"4;
"VSS918"
$PN"DA41"4;
"VSS919"
$PN"DA48"4;
"VSS920"
$PN"DA50"4;
"VSS921"
$PN"DA54"4;
"VSS922"
$PN"DA56"4;
"VSS923"
$PN"DA58"4;
"VSS924"
$PN"DA60"4;
"VSS925"
$PN"DA62"4;
"VSS926"
$PN"DA66"4;
"VSS927"
$PN"DA72"4;
"VSS928"
$PN"DA74"4;
"VSS929"
$PN"DA80"4;
"VSS930"
$PN"DA82"4;
"VSS931"
$PN"DA84"4;
"VSS932"
$PN"DA88"4;
"VSS933"
$PN"DB12"4;
"VSS935"
$PN"DB22"4;
"VSS936"
$PN"DB28"4;
"VSS937"
$PN"DB32"4;
"VSS938"
$PN"DB38"4;
"VSS939"
$PN"DB4"4;
"VSS940"
$PN"DB40"4;
"VSS941"
$PN"DB47"4;
"VSS942"
$PN"DB57"4;
"VSS943"
$PN"DB65"4;
"VSS944"
$PN"DB71"4;
"VSS946"
$PN"DB77"4;
"VSS947"
$PN"DB8"4;
"VSS948"
$PN"DB87"4;
%"UNIVERSAL_GND"
"1","(2125,-775)","0","logical_power","I6";
;
CDS_LIB"logical_power"
HDL_POWER"GND";
"A"3;
%"UNIVERSAL_GND"
"1","(2250,-775)","0","logical_power","I7";
;
CDS_LIB"logical_power"
HDL_POWER"GND";
"A"2;
%"SOCKET4677_AZIF0045P001C01CS"
"36","(3700,1750)","0","pure_quanta","I8";
;
PART_NUMBER"DGA^7000023"
PART_TYPE"SMLF"
MATERIAL"IO"
VALUE"SOCKET4677_AZIF0045-P001C01CS"
$LOCATION"U1"
CDS_LIB"pure_quanta"
NEEDS_NO_SIZE"TRUE"
CDS_LMAN_SYM_OUTLINE"-1050,2150,1050,-2100"
CDS_LOCATION"U1"
$SEC"36"
CDS_SEC"36";
"VSS383"
$PN"CJ76"2;
"VSS396"
$PN"CK4"2;
"VSS542"
$PN"BR35"1;
"VSS543"
$PN"BR37"1;
"VSS545"
$PN"BR39"1;
"VSS546"
$PN"BR41"1;
"VSS547"
$PN"BR43"1;
"VSS548"
$PN"BR45"1;
"VSS549"
$PN"BR48"1;
"VSS550"
$PN"BR50"1;
"VSS551"
$PN"BR52"1;
"VSS552"
$PN"BR54"1;
"VSS555"
$PN"BR56"1;
"VSS556"
$PN"BR58"1;
"VSS557"
$PN"BR64"1;
"VSS559"
$PN"BR66"1;
"VSS560"
$PN"BR68"1;
"VSS561"
$PN"BR70"1;
"VSS563"
$PN"BR72"1;
"VSS564"
$PN"BR74"1;
"VSS565"
$PN"BR76"1;
"VSS566"
$PN"BR80"1;
"VSS567"
$PN"BR82"1;
"VSS568"
$PN"BR84"1;
"VSS569"
$PN"BR86"1;
"VSS570"
$PN"BR88"1;
"VSS573"
$PN"BR90"1;
"VSS574"
$PN"BT12"1;
"VSS575"
$PN"BT16"1;
"VSS576"
$PN"BT20"1;
"VSS577"
$PN"BT4"1;
"VSS578"
$PN"BT8"1;
"VSS579"
$PN"BU15"1;
"VSS580"
$PN"BU19"1;
"VSS581"
$PN"BU21"1;
"VSS582"
$PN"BU23"1;
"VSS584"
$PN"BU25"1;
"VSS585"
$PN"BU31"1;
"VSS586"
$PN"BU7"1;
"VSS587"
$PN"BV12"1;
"VSS588"
$PN"BV16"1;
"VSS589"
$PN"BV18"1;
"VSS590"
$PN"BV2"1;
"VSS591"
$PN"BV20"1;
"VSS592"
$PN"BV4"1;
"VSS593"
$PN"BV6"1;
"VSS594"
$PN"BV8"1;
"VSS596"
$PN"BW13"1;
"VSS597"
$PN"BW17"1;
"VSS598"
$PN"BW27"1;
"VSS599"
$PN"BW29"1;
"VSS600"
$PN"BW3"1;
"VSS601"
$PN"BW31"1;
"VSS602"
$PN"BW5"1;
"VSS603"
$PN"BW9"1;
"VSS604"
$PN"BY12"1;
"VSS605"
$PN"BY16"1;
"VSS606"
$PN"BY20"1;
"VSS607"
$PN"BY4"1;
"VSS608"
$PN"BY8"1;
"VSS620"
$PN"CA3"1;
"VSS621"
$PN"CA31"1;
"VSS622"
$PN"CB12"1;
"VSS623"
$PN"CB16"1;
"VSS624"
$PN"CB20"1;
"VSS625"
$PN"CB22"1;
"VSS626"
$PN"CB24"1;
"VSS627"
$PN"CB26"1;
"VSS628"
$PN"CB28"1;
"VSS629"
$PN"CB32"1;
"VSS630"
$PN"CB34"1;
"VSS631"
$PN"CB36"1;
"VSS632"
$PN"CB38"1;
"VSS633"
$PN"CB4"1;
"VSS634"
$PN"CB40"1;
"VSS635"
$PN"CB42"1;
"VSS636"
$PN"CB44"1;
"VSS637"
$PN"CB47"1;
"VSS638"
$PN"CB49"1;
"VSS639"
$PN"CB51"1;
"VSS640"
$PN"CB53"1;
"VSS641"
$PN"CB55"2;
"VSS642"
$PN"CB57"2;
"VSS643"
$PN"CB59"2;
"VSS644"
$PN"CB63"2;
"VSS645"
$PN"CB65"2;
"VSS646"
$PN"CB67"2;
"VSS647"
$PN"CB69"2;
"VSS648"
$PN"CB71"2;
"VSS649"
$PN"CB73"2;
"VSS650"
$PN"CB79"2;
"VSS651"
$PN"CB8"1;
"VSS652"
$PN"CB81"2;
"VSS653"
$PN"CB83"2;
"VSS654"
$PN"CB85"2;
"VSS655"
$PN"CB87"2;
"VSS656"
$PN"CB89"2;
"VSS660"
$PN"CC13"2;
"VSS661"
$PN"CC17"2;
"VSS664"
$PN"CC31"2;
"VSS665"
$PN"CC5"2;
"VSS666"
$PN"CC62"2;
"VSS667"
$PN"CC70"2;
"VSS668"
$PN"CC72"2;
"VSS669"
$PN"CC74"2;
"VSS670"
$PN"CC9"2;
"VSS671"
$PN"CD12"2;
"VSS672"
$PN"CD16"2;
"VSS673"
$PN"CD20"2;
"VSS674"
$PN"CD4"2;
"VSS675"
$PN"CD61"2;
"VSS676"
$PN"CD75"2;
"VSS677"
$PN"CD77"2;
"VSS678"
$PN"CD8"2;
"VSS680"
$PN"CE3"2;
"VSS681"
$PN"CE60"2;
"VSS682"
$PN"CE66"2;
"VSS683"
$PN"CE72"2;
"VSS684"
$PN"CE76"2;
"VSS685"
$PN"CE78"2;
"VSS686"
$PN"CF12"2;
"VSS687"
$PN"CF16"2;
"VSS688"
$PN"CF20"2;
"VSS689"
$PN"CF4"2;
"VSS691"
$PN"CF69"2;
"VSS692"
$PN"CF71"2;
"VSS693"
$PN"CF8"2;
"VSS694"
$PN"CG1"2;
"VSS695"
$PN"CG13"2;
"VSS696"
$PN"CG17"2;
"VSS697"
$PN"CG21"2;
"VSS698"
$PN"CG23"2;
"VSS701"
$PN"CG25"2;
"VSS703"
$PN"CG5"2;
"VSS704"
$PN"CG62"2;
"VSS706"
$PN"CG64"2;
"VSS707"
$PN"CG70"2;
"VSS708"
$PN"CG72"2;
"VSS710"
$PN"CG74"2;
"VSS713"
$PN"CG78"2;
"VSS716"
$PN"CG9"2;
"VSS718"
$PN"CH12"2;
"VSS720"
$PN"CH16"2;
"VSS721"
$PN"CH20"2;
"VSS722"
$PN"CH4"2;
"VSS727"
$PN"CH67"2;
"VSS728"
$PN"CH73"2;
"VSS729"
$PN"CH79"2;
"VSS730"
$PN"CH8"2;
"VSS731"
$PN"CH83"2;
"VSS732"
$PN"CH85"2;
"VSS733"
$PN"CH87"2;
"VSS734"
$PN"CH89"2;
"VSS736"
$PN"CJ60"2;
"VSS737"
$PN"CJ80"2;
"VSS740"
$PN"CK12"2;
"VSS741"
$PN"CK16"2;
"VSS742"
$PN"CK20"2;
"VSS743"
$PN"CK26"2;
"VSS746"
$PN"CK8"2;
%"UNIVERSAL_GND"
"1","(5150,-775)","0","logical_power","I9";
;
CDS_LIB"logical_power"
HDL_POWER"GND";
"A"1;
END.
